# S9S_MB_2U (Grand Teton) — schematic netlist excerpt (pin names and nets, part order shuffled) for the footprints in the layout excerpt that follows; sources: Cadence DE-HDL packaged netlist, KiCad conversion of 03242023_DA0F0TMBIJ0_F0T_Motherboard_J_brd_V01_OCP.brd

PC2204  Q_CAP  10UF 16V 10% EMPTY  pkg C0805  page 193 : A = P3V3_E1S_0_R ; B = GND

PU174  MOSFET_N  BSS138K EMPTY  pkg SMLF  page 299
  DRAIN  = FM_HBM_VPP_SEL_CPU1_D
  GATE  = FM_HBM2_HBM3_VPP_SEL
  SOURCE  = SH_PVPP_HBM_CPU1_N

R4901  Q_RES  82K 1% CHIP  pkg 0402LF  page 301 : A = P12V_PSU_FUSE ; B = HSC_EN

(kicad_pcb
	(version 20260206)
	(generator "pcbnew")
	(generator_version "10.0")
	(general
		(thickness 1.6)
		(legacy_teardrops no)
	)
	(paper "A4")
	(title_block
		(title "03242023_DA0F0TMBIJ0_F0T_Motherboard_J_brd_V01_OCP.brd")
		(comment 1 "Grand Teton / footprints 894-896 of 6105")
	)
	(layers
		(0 "F.Cu" signal "TOP")
		(4 "In1.Cu" signal "GND")
		(6 "In2.Cu" signal "IN1")
		(8 "In3.Cu" signal "GND1")
		(10 "In4.Cu" signal "IN2")
		(12 "In5.Cu" signal "GND2")
		(14 "In6.Cu" signal "IN3")
		(16 "In7.Cu" signal "GND3")
		(18 "In8.Cu" signal "VCC")
		(20 "In9.Cu" signal "VCC1")
		(22 "In10.Cu" signal "GND4")
		(24 "In11.Cu" signal "IN4")
		(26 "In12.Cu" signal "GND5")
		(28 "In13.Cu" signal "IN5")
		(30 "In14.Cu" signal "GND6")
		(32 "In15.Cu" signal "IN6")
		(34 "In16.Cu" signal "GND7")
		(2 "B.Cu" signal "BOTTOM")
		(9 "F.Adhes" user "F.Adhesive")
		(11 "B.Adhes" user "B.Adhesive")
		(13 "F.Paste" user "Package Geometry/Pastemask Top")
		(15 "B.Paste" user "Package Geometry/Pastemask Bottom")
		(5 "F.SilkS" user "Ref Des/Silkscreen Top")
		(7 "B.SilkS" user "Ref Des/Silkscreen Bottom")
		(1 "F.Mask" user "Board Geometry/Soldermask Top")
		(3 "B.Mask" user "Board Geometry/Soldermask Bottom")
		(17 "Dwgs.User" user "User.Drawings")
		(19 "Cmts.User" user "User.Comments")
		(21 "Eco1.User" user "User.Eco1")
		(23 "Eco2.User" user "User.Eco2")
		(25 "Edge.Cuts" user "Board Geometry/Outline")
		(27 "Margin" user)
		(31 "F.CrtYd" user "Package Geometry/Place Bound Top")
		(29 "B.CrtYd" user "Package Geometry/Place Bound Bottom")
		(35 "F.Fab" user "Ref Des/Assembly Top")
		(33 "B.Fab" user "Ref Des/Assembly Bottom")
	)
	(footprint ""
		(layer "F.Cu")
		(at 187.842652 -424.87977 -90)
		(property "Reference" "R4901"
			(at 0 0 270)
			(layer "F.SilkS")
			(hide yes)
			(effects
				(font
					(size 1.27 1.27)
				)
			)
		)
		(property "Value" ""
			(at 0 0 270)
			(layer "F.Fab")
			(effects
				(font
					(size 1.27 1.27)
				)
			)
		)
		(duplicate_pad_numbers_are_jumpers no)
		(fp_line
			(start -0.7874 0.4064)
			(end -0.7874 -0.4064)
			(stroke
				(width 0.1524)
				(type default)
			)
			(layer "F.SilkS")
		)
		(fp_line
			(start 0.7874 0.4064)
			(end -0.7874 0.4064)
			(stroke
				(width 0.1524)
				(type default)
			)
			(layer "F.SilkS")
		)
		(fp_line
			(start -0.7874 -0.4064)
			(end 0.7874 -0.4064)
			(stroke
				(width 0.1524)
				(type default)
			)
			(layer "F.SilkS")
		)
		(fp_line
			(start 0.7874 -0.4064)
			(end 0.7874 0.4064)
			(stroke
				(width 0.1524)
				(type default)
			)
			(layer "F.SilkS")
		)
		(fp_line
			(start -0.67945 0.3048)
			(end -0.67945 -0.305054)
			(stroke
				(width 0.1)
				(type default)
			)
			(layer "F.Fab")
		)
		(fp_line
			(start -0.12065 0.3048)
			(end -0.67945 0.3048)
			(stroke
				(width 0.1)
				(type default)
			)
			(layer "F.Fab")
		)
		(fp_line
			(start 0.120396 0.3048)
			(end 0.120396 0.2794)
			(stroke
				(width 0.1)
				(type default)
			)
			(layer "F.Fab")
		)
		(fp_line
			(start 0.67945 0.3048)
			(end 0.120396 0.3048)
			(stroke
				(width 0.1)
				(type default)
			)
			(layer "F.Fab")
		)
		(fp_line
			(start -0.12065 0.2794)
			(end -0.12065 0.3048)
			(stroke
				(width 0.1)
				(type default)
			)
			(layer "F.Fab")
		)
		(fp_line
			(start 0.120396 0.2794)
			(end -0.12065 0.2794)
			(stroke
				(width 0.1)
				(type default)
			)
			(layer "F.Fab")
		)
		(fp_line
			(start -0.12065 -0.2794)
			(end 0.12065 -0.2794)
			(stroke
				(width 0.1)
				(type default)
			)
			(layer "F.Fab")
		)
		(fp_line
			(start 0.12065 -0.2794)
			(end 0.12065 -0.3048)
			(stroke
				(width 0.1)
				(type default)
			)
			(layer "F.Fab")
		)
		(fp_line
			(start 0.12065 -0.3048)
			(end 0.67945 -0.3048)
			(stroke
				(width 0.1)
				(type default)
			)
			(layer "F.Fab")
		)
		(fp_line
			(start 0.67945 -0.3048)
			(end 0.67945 0.3048)
			(stroke
				(width 0.1)
				(type default)
			)
			(layer "F.Fab")
		)
		(fp_line
			(start -0.67945 -0.305054)
			(end -0.12065 -0.305054)
			(stroke
				(width 0.1)
				(type default)
			)
			(layer "F.Fab")
		)
		(fp_line
			(start -0.12065 -0.305054)
			(end -0.12065 -0.2794)
			(stroke
				(width 0.1)
				(type default)
			)
			(layer "F.Fab")
		)
		(pad "1" smd circle
			(at -0.40005 0 270)
			(size 0 0)
			(layers "F.Cu" "F.Mask" "F.Paste")
			(net "P12V_PSU_FUSE")
		)
		(pad "2" smd circle
			(at 0.40005 0 270)
			(size 0 0)
			(layers "F.Cu" "F.Mask" "F.Paste")
			(net "HSC_EN")
		)
	)
	(footprint ""
		(layer "F.Cu")
		(at 118.6561 -362.501942 -90)
		(property "Reference" "PU174"
			(at -2.940558 0.323342 0)
			(unlocked yes)
			(layer "F.SilkS")
			(effects
				(font
					(size 0.7874 0.5842)
					(thickness 0.1524)
				)
			)
		)
		(property "Value" ""
			(at 0 0 270)
			(layer "F.Fab")
			(effects
				(font
					(size 1.27 1.27)
				)
			)
		)
		(duplicate_pad_numbers_are_jumpers no)
		(fp_line
			(start -1.949958 1.610106)
			(end -1.949958 -1.610106)
			(stroke
				(width 0.1524)
				(type default)
			)
			(layer "F.SilkS")
		)
		(fp_line
			(start 1.949958 1.610106)
			(end -1.949958 1.610106)
			(stroke
				(width 0.1524)
				(type default)
			)
			(layer "F.SilkS")
		)
		(fp_line
			(start 1.949958 -1.560068)
			(end 1.949958 1.610106)
			(stroke
				(width 0.1524)
				(type default)
			)
			(layer "F.SilkS")
		)
		(fp_line
			(start -1.949958 -1.610106)
			(end 1.949958 -1.610106)
			(stroke
				(width 0.1524)
				(type default)
			)
			(layer "F.SilkS")
		)
		(fp_line
			(start -0.750062 1.560068)
			(end -0.750062 -1.560068)
			(stroke
				(width 0.1)
				(type default)
			)
			(layer "F.Fab")
		)
		(fp_line
			(start 0.750062 1.560068)
			(end -0.750062 1.560068)
			(stroke
				(width 0.1)
				(type default)
			)
			(layer "F.Fab")
		)
		(fp_line
			(start -0.750062 -1.560068)
			(end 0.750062 -1.560068)
			(stroke
				(width 0.1)
				(type default)
			)
			(layer "F.Fab")
		)
		(fp_line
			(start 0.750062 -1.560068)
			(end 0.750062 1.560068)
			(stroke
				(width 0.1)
				(type default)
			)
			(layer "F.Fab")
		)
		(pad "D" smd rect
			(at 1.100074 0 180)
			(size 1.016 1.4224)
			(layers "F.Cu" "F.Mask" "F.Paste")
			(net "FM_HBM_VPP_SEL_CPU1_D")
		)
		(pad "G" smd rect
			(at -1.100074 -0.94996 180)
			(size 1.016 1.4224)
			(layers "F.Cu" "F.Mask" "F.Paste")
			(net "FM_HBM2_HBM3_VPP_SEL")
		)
		(pad "S" smd rect
			(at -1.100074 0.94996 180)
			(size 1.016 1.4224)
			(layers "F.Cu" "F.Mask" "F.Paste")
			(net "SH_PVPP_HBM_CPU1_N")
		)
	)
	(footprint ""
		(layer "F.Cu")
		(at 194.2719 -65.225168 -90)
		(property "Reference" "PC2204"
			(at 0 0 270)
			(layer "F.SilkS")
			(hide yes)
			(effects
				(font
					(size 1.27 1.27)
				)
			)
		)
		(property "Value" ""
			(at 0 0 270)
			(layer "F.Fab")
			(effects
				(font
					(size 1.27 1.27)
				)
			)
		)
		(duplicate_pad_numbers_are_jumpers no)
		(fp_line
			(start -1.524 0.762)
			(end -1.524 -0.762)
			(stroke
				(width 0.1524)
				(type default)
			)
			(layer "F.SilkS")
		)
		(fp_line
			(start 1.524 0.762)
			(end -1.524 0.762)
			(stroke
				(width 0.1524)
				(type default)
			)
			(layer "F.SilkS")
		)
		(fp_line
			(start -1.524 -0.762)
			(end 1.524 -0.762)
			(stroke
				(width 0.1524)
				(type default)
			)
			(layer "F.SilkS")
		)
		(fp_line
			(start 1.524 -0.762)
			(end 1.524 0.762)
			(stroke
				(width 0.1524)
				(type default)
			)
			(layer "F.SilkS")
		)
		(fp_line
			(start -1.1049 0.724916)
			(end 1.1049 0.724916)
			(stroke
				(width 0.1)
				(type default)
			)
			(layer "F.Fab")
		)
		(fp_line
			(start 1.1049 0.724916)
			(end 1.1049 -0.724916)
			(stroke
				(width 0.1)
				(type default)
			)
			(layer "F.Fab")
		)
		(fp_line
			(start -1.1049 -0.724916)
			(end -1.1049 0.724916)
			(stroke
				(width 0.1)
				(type default)
			)
			(layer "F.Fab")
		)
		(fp_line
			(start 1.1049 -0.724916)
			(end -1.1049 -0.724916)
			(stroke
				(width 0.1)
				(type default)
			)
			(layer "F.Fab")
		)
		(pad "1" smd rect
			(at -0.889 0 90)
			(size 1.016 1.27)
			(layers "F.Cu" "F.Mask" "F.Paste")
			(net "P3V3_E1S_0_R")
		)
		(pad "2" smd rect
			(at 0.889 0 90)
			(size 1.016 1.27)
			(layers "F.Cu" "F.Mask" "F.Paste")
			(net "GND")
		)
	)
)
